# S9S_MB_2U (Grand Teton) — schematic netlist excerpt (pin names and nets, part order shuffled) for the footprints in the layout excerpt that follows; sources: Cadence DE-HDL packaged netlist, KiCad conversion of 03242023_DA0F0TMBIJ0_F0T_Motherboard_J_brd_V01_OCP.brd

U52  APX80929SAG7  APX809-29SAG-7 IC  pkg SOT23_123XI  page 158
  GND  = GND
  RESET_L  = HP_OCP_V3_1_RST
  VCC  = P3V3_OCP_SFF

R3715  Q_RES  0 5% CHIP  pkg 0402LF  page 233 : A = SMB_LM75_0_3V3AUX_SCL_R ; B = SMB_LM75_0_3V3AUX_SCL
C823  Q_CAP_DIFFBUS  DIFF BUS_0.22UF 6.3V 20% X6S  pkg C0201  page 175 : \1\ = P5E_CPU1_PE1_TX_C_DP<7> ; \2\ = P5E_CPU1_PE1_TX_DP<7>

(kicad_pcb
	(version 20260206)
	(generator "pcbnew")
	(generator_version "10.0")
	(general
		(thickness 1.6)
		(legacy_teardrops no)
	)
	(paper "A4")
	(title_block
		(title "03242023_DA0F0TMBIJ0_F0T_Motherboard_J_brd_V01_OCP.brd")
		(comment 1 "Grand Teton / footprints 1105-1107 of 6105")
	)
	(layers
		(0 "F.Cu" signal "TOP")
		(4 "In1.Cu" signal "GND")
		(6 "In2.Cu" signal "IN1")
		(8 "In3.Cu" signal "GND1")
		(10 "In4.Cu" signal "IN2")
		(12 "In5.Cu" signal "GND2")
		(14 "In6.Cu" signal "IN3")
		(16 "In7.Cu" signal "GND3")
		(18 "In8.Cu" signal "VCC")
		(20 "In9.Cu" signal "VCC1")
		(22 "In10.Cu" signal "GND4")
		(24 "In11.Cu" signal "IN4")
		(26 "In12.Cu" signal "GND5")
		(28 "In13.Cu" signal "IN5")
		(30 "In14.Cu" signal "GND6")
		(32 "In15.Cu" signal "IN6")
		(34 "In16.Cu" signal "GND7")
		(2 "B.Cu" signal "BOTTOM")
		(9 "F.Adhes" user "F.Adhesive")
		(11 "B.Adhes" user "B.Adhesive")
		(13 "F.Paste" user "Package Geometry/Pastemask Top")
		(15 "B.Paste" user "Package Geometry/Pastemask Bottom")
		(5 "F.SilkS" user "Ref Des/Silkscreen Top")
		(7 "B.SilkS" user "Ref Des/Silkscreen Bottom")
		(1 "F.Mask" user "Board Geometry/Soldermask Top")
		(3 "B.Mask" user "Board Geometry/Soldermask Bottom")
		(17 "Dwgs.User" user "User.Drawings")
		(19 "Cmts.User" user "User.Comments")
		(21 "Eco1.User" user "User.Eco1")
		(23 "Eco2.User" user "User.Eco2")
		(25 "Edge.Cuts" user "Board Geometry/Outline")
		(27 "Margin" user)
		(31 "F.CrtYd" user "Package Geometry/Place Bound Top")
		(29 "B.CrtYd" user "Package Geometry/Place Bound Bottom")
		(35 "F.Fab" user "Ref Des/Assembly Top")
		(33 "B.Fab" user "Ref Des/Assembly Bottom")
	)
	(footprint ""
		(layer "F.Cu")
		(at 37.860478 -16.099536 90)
		(property "Reference" "C823"
			(at 0 0 90)
			(layer "F.SilkS")
			(hide yes)
			(effects
				(font
					(size 1.27 1.27)
				)
			)
		)
		(property "Value" ""
			(at 0 0 90)
			(layer "F.Fab")
			(effects
				(font
					(size 1.27 1.27)
				)
			)
		)
		(duplicate_pad_numbers_are_jumpers no)
		(fp_line
			(start 0.299974 -0.150114)
			(end 0.299974 0.150114)
			(stroke
				(width 0.1)
				(type default)
			)
			(layer "F.Fab")
		)
		(fp_line
			(start -0.299974 -0.150114)
			(end 0.299974 -0.150114)
			(stroke
				(width 0.1)
				(type default)
			)
			(layer "F.Fab")
		)
		(fp_line
			(start 0.299974 0.150114)
			(end -0.299974 0.150114)
			(stroke
				(width 0.1)
				(type default)
			)
			(layer "F.Fab")
		)
		(fp_line
			(start -0.299974 0.150114)
			(end -0.299974 -0.150114)
			(stroke
				(width 0.1)
				(type default)
			)
			(layer "F.Fab")
		)
		(pad "1" smd rect
			(at -0.2667 0 90)
			(size 0.3048 0.381)
			(layers "F.Cu" "F.Mask" "F.Paste")
			(net "P5E_CPU1_PE1_TX_C_DP<7>")
		)
		(pad "2" smd rect
			(at 0.2667 0 90)
			(size 0.3048 0.381)
			(layers "F.Cu" "F.Mask" "F.Paste")
			(net "P5E_CPU1_PE1_TX_DP<7>")
		)
	)
	(footprint ""
		(layer "F.Cu")
		(at 388.72541 -35.731196 90)
		(property "Reference" "U52"
			(at 3.957828 -0.994918 0)
			(unlocked yes)
			(layer "F.SilkS")
			(effects
				(font
					(size 0.7874 0.5842)
					(thickness 0.1524)
				)
				(justify left)
			)
		)
		(property "Value" ""
			(at 0 0 90)
			(layer "F.Fab")
			(effects
				(font
					(size 1.27 1.27)
				)
			)
		)
		(duplicate_pad_numbers_are_jumpers no)
		(fp_line
			(start 1.759712 -1.500124)
			(end 1.759712 1.500124)
			(stroke
				(width 0.1524)
				(type default)
			)
			(layer "F.SilkS")
		)
		(fp_line
			(start -1.759712 -1.500124)
			(end 1.759712 -1.500124)
			(stroke
				(width 0.1524)
				(type default)
			)
			(layer "F.SilkS")
		)
		(fp_line
			(start 1.759712 1.500124)
			(end -1.759712 1.500124)
			(stroke
				(width 0.1524)
				(type default)
			)
			(layer "F.SilkS")
		)
		(fp_line
			(start -1.759712 1.500124)
			(end -1.759712 -1.500124)
			(stroke
				(width 0.1524)
				(type default)
			)
			(layer "F.SilkS")
		)
		(fp_line
			(start 0.700024 -1.500124)
			(end 0.700024 1.500124)
			(stroke
				(width 0.1)
				(type default)
			)
			(layer "F.Fab")
		)
		(fp_line
			(start -0.700024 -1.500124)
			(end 0.700024 -1.500124)
			(stroke
				(width 0.1)
				(type default)
			)
			(layer "F.Fab")
		)
		(fp_line
			(start 0.700024 1.500124)
			(end -0.700024 1.500124)
			(stroke
				(width 0.1)
				(type default)
			)
			(layer "F.Fab")
		)
		(fp_line
			(start -0.700024 1.500124)
			(end -0.700024 -1.500124)
			(stroke
				(width 0.1)
				(type default)
			)
			(layer "F.Fab")
		)
		(pad "1" smd rect
			(at -1.150112 -0.94996)
			(size 0.6604 0.9652)
			(layers "F.Cu" "F.Mask" "F.Paste")
			(net "GND")
		)
		(pad "2" smd rect
			(at -1.150112 0.94996)
			(size 0.6604 0.9652)
			(layers "F.Cu" "F.Mask" "F.Paste")
			(net "HP_OCP_V3_1_RST")
		)
		(pad "3" smd rect
			(at 1.150112 0)
			(size 0.6604 0.9652)
			(layers "F.Cu" "F.Mask" "F.Paste")
			(net "P3V3_OCP_SFF")
		)
	)
	(footprint ""
		(layer "F.Cu")
		(at 54.242716 -110.93069 180)
		(property "Reference" "R3715"
			(at 0 0 180)
			(layer "F.SilkS")
			(hide yes)
			(effects
				(font
					(size 1.27 1.27)
				)
			)
		)
		(property "Value" ""
			(at 0 0 180)
			(layer "F.Fab")
			(effects
				(font
					(size 1.27 1.27)
				)
			)
		)
		(duplicate_pad_numbers_are_jumpers no)
		(fp_line
			(start 0.7874 0.4064)
			(end -0.7874 0.4064)
			(stroke
				(width 0.1524)
				(type default)
			)
			(layer "F.SilkS")
		)
		(fp_line
			(start 0.7874 -0.4064)
			(end 0.7874 0.4064)
			(stroke
				(width 0.1524)
				(type default)
			)
			(layer "F.SilkS")
		)
		(fp_line
			(start -0.7874 0.4064)
			(end -0.7874 -0.4064)
			(stroke
				(width 0.1524)
				(type default)
			)
			(layer "F.SilkS")
		)
		(fp_line
			(start -0.7874 -0.4064)
			(end 0.7874 -0.4064)
			(stroke
				(width 0.1524)
				(type default)
			)
			(layer "F.SilkS")
		)
		(fp_line
			(start 0.67945 0.3048)
			(end 0.120396 0.3048)
			(stroke
				(width 0.1)
				(type default)
			)
			(layer "F.Fab")
		)
		(fp_line
			(start 0.67945 -0.3048)
			(end 0.67945 0.3048)
			(stroke
				(width 0.1)
				(type default)
			)
			(layer "F.Fab")
		)
		(fp_line
			(start 0.12065 -0.2794)
			(end 0.12065 -0.3048)
			(stroke
				(width 0.1)
				(type default)
			)
			(layer "F.Fab")
		)
		(fp_line
			(start 0.12065 -0.3048)
			(end 0.67945 -0.3048)
			(stroke
				(width 0.1)
				(type default)
			)
			(layer "F.Fab")
		)
		(fp_line
			(start 0.120396 0.3048)
			(end 0.120396 0.2794)
			(stroke
				(width 0.1)
				(type default)
			)
			(layer "F.Fab")
		)
		(fp_line
			(start 0.120396 0.2794)
			(end -0.12065 0.2794)
			(stroke
				(width 0.1)
				(type default)
			)
			(layer "F.Fab")
		)
		(fp_line
			(start -0.12065 0.3048)
			(end -0.67945 0.3048)
			(stroke
				(width 0.1)
				(type default)
			)
			(layer "F.Fab")
		)
		(fp_line
			(start -0.12065 0.2794)
			(end -0.12065 0.3048)
			(stroke
				(width 0.1)
				(type default)
			)
			(layer "F.Fab")
		)
		(fp_line
			(start -0.12065 -0.2794)
			(end 0.12065 -0.2794)
			(stroke
				(width 0.1)
				(type default)
			)
			(layer "F.Fab")
		)
		(fp_line
			(start -0.12065 -0.305054)
			(end -0.12065 -0.2794)
			(stroke
				(width 0.1)
				(type default)
			)
			(layer "F.Fab")
		)
		(fp_line
			(start -0.67945 0.3048)
			(end -0.67945 -0.305054)
			(stroke
				(width 0.1)
				(type default)
			)
			(layer "F.Fab")
		)
		(fp_line
			(start -0.67945 -0.305054)
			(end -0.12065 -0.305054)
			(stroke
				(width 0.1)
				(type default)
			)
			(layer "F.Fab")
		)
		(pad "1" smd circle
			(at -0.40005 0 180)
			(size 0 0)
			(layers "F.Cu" "F.Mask" "F.Paste")
			(net "SMB_LM75_0_3V3AUX_SCL_R")
		)
		(pad "2" smd circle
			(at 0.40005 0 180)
			(size 0 0)
			(layers "F.Cu" "F.Mask" "F.Paste")
			(net "SMB_LM75_0_3V3AUX_SCL")
		)
	)
)
